(kicad_pcb
	(version 20260206)
	(generator "pcbnew")
	(generator_version "10.0")
	(general
		(thickness 1.6)
		(legacy_teardrops no)
	)
	(paper "A4")
	(title_block
		(title "04192023_DAF0TMB3IC0_F0TG_MB_C_brd_V02_OCP.brd")
		(comment 1 "Grand Teton / footprints 1804-1807 of 8354")
	)
	(layers
		(0 "F.Cu" signal "TOP")
		(4 "In1.Cu" signal "GND")
		(6 "In2.Cu" signal "IN1")
		(8 "In3.Cu" signal "GND1")
		(10 "In4.Cu" signal "IN2")
		(12 "In5.Cu" signal "GND2")
		(14 "In6.Cu" signal "IN3")
		(16 "In7.Cu" signal "GND3")
		(18 "In8.Cu" signal "VCC")
		(20 "In9.Cu" signal "VCC1")
		(22 "In10.Cu" signal "GND4")
		(24 "In11.Cu" signal "IN4")
		(26 "In12.Cu" signal "GND5")
		(28 "In13.Cu" signal "IN5")
		(30 "In14.Cu" signal "GND6")
		(32 "In15.Cu" signal "IN6")
		(34 "In16.Cu" signal "GND7")
		(2 "B.Cu" signal "BOTTOM")
		(9 "F.Adhes" user "F.Adhesive")
		(11 "B.Adhes" user "B.Adhesive")
		(13 "F.Paste" user "Package Geometry/Pastemask Top")
		(15 "B.Paste" user "Package Geometry/Pastemask Bottom")
		(5 "F.SilkS" user "Ref Des/Silkscreen Top")
		(7 "B.SilkS" user "Ref Des/Silkscreen Bottom")
		(1 "F.Mask" user "Board Geometry/Soldermask Top")
		(3 "B.Mask" user "Board Geometry/Soldermask Bottom")
		(17 "Dwgs.User" user "User.Drawings")
		(19 "Cmts.User" user "User.Comments")
		(21 "Eco1.User" user "User.Eco1")
		(23 "Eco2.User" user "User.Eco2")
		(25 "Edge.Cuts" user "Board Geometry/Outline")
		(27 "Margin" user)
		(31 "F.CrtYd" user "Package Geometry/Place Bound Top")
		(29 "B.CrtYd" user "Package Geometry/Place Bound Bottom")
		(35 "F.Fab" user "Ref Des/Assembly Top")
		(33 "B.Fab" user "Ref Des/Assembly Bottom")
	)
	(footprint ""
		(layer "F.Cu")
		(at 327.323958 -193.163952 -90)
		(property "Reference" "R415"
			(at 0 0 270)
			(layer "F.SilkS")
			(hide yes)
			(effects
				(font
					(size 1.27 1.27)
				)
			)
		)
		(property "Value" ""
			(at 0 0 270)
			(layer "F.Fab")
			(effects
				(font
					(size 1.27 1.27)
				)
			)
		)
		(duplicate_pad_numbers_are_jumpers no)
		(fp_line
			(start -0.7874 0.4064)
			(end -0.7874 -0.4064)
			(stroke
				(width 0.1524)
				(type default)
			)
			(layer "F.SilkS")
		)
		(fp_line
			(start 0.7874 0.4064)
			(end -0.7874 0.4064)
			(stroke
				(width 0.1524)
				(type default)
			)
			(layer "F.SilkS")
		)
		(fp_line
			(start -0.7874 -0.4064)
			(end 0.7874 -0.4064)
			(stroke
				(width 0.1524)
				(type default)
			)
			(layer "F.SilkS")
		)
		(fp_line
			(start 0.7874 -0.4064)
			(end 0.7874 0.4064)
			(stroke
				(width 0.1524)
				(type default)
			)
			(layer "F.SilkS")
		)
		(fp_line
			(start -0.67945 0.3048)
			(end -0.67945 -0.305054)
			(stroke
				(width 0.1)
				(type default)
			)
			(layer "F.Fab")
		)
		(fp_line
			(start -0.12065 0.3048)
			(end -0.67945 0.3048)
			(stroke
				(width 0.1)
				(type default)
			)
			(layer "F.Fab")
		)
		(fp_line
			(start 0.120396 0.3048)
			(end 0.120396 0.2794)
			(stroke
				(width 0.1)
				(type default)
			)
			(layer "F.Fab")
		)
		(fp_line
			(start 0.67945 0.3048)
			(end 0.120396 0.3048)
			(stroke
				(width 0.1)
				(type default)
			)
			(layer "F.Fab")
		)
		(fp_line
			(start -0.12065 0.2794)
			(end -0.12065 0.3048)
			(stroke
				(width 0.1)
				(type default)
			)
			(layer "F.Fab")
		)
		(fp_line
			(start 0.120396 0.2794)
			(end -0.12065 0.2794)
			(stroke
				(width 0.1)
				(type default)
			)
			(layer "F.Fab")
		)
		(fp_line
			(start -0.12065 -0.2794)
			(end 0.12065 -0.2794)
			(stroke
				(width 0.1)
				(type default)
			)
			(layer "F.Fab")
		)
		(fp_line
			(start 0.12065 -0.2794)
			(end 0.12065 -0.3048)
			(stroke
				(width 0.1)
				(type default)
			)
			(layer "F.Fab")
		)
		(fp_line
			(start 0.12065 -0.3048)
			(end 0.67945 -0.3048)
			(stroke
				(width 0.1)
				(type default)
			)
			(layer "F.Fab")
		)
		(fp_line
			(start 0.67945 -0.3048)
			(end 0.67945 0.3048)
			(stroke
				(width 0.1)
				(type default)
			)
			(layer "F.Fab")
		)
		(fp_line
			(start -0.67945 -0.305054)
			(end -0.12065 -0.305054)
			(stroke
				(width 0.1)
				(type default)
			)
			(layer "F.Fab")
		)
		(fp_line
			(start -0.12065 -0.305054)
			(end -0.12065 -0.2794)
			(stroke
				(width 0.1)
				(type default)
			)
			(layer "F.Fab")
		)
		(pad "1" smd circle
			(at -0.40005 0 270)
			(size 0 0)
			(layers "F.Cu" "F.Mask" "F.Paste")
			(net "CPU0_XTRIG_L6")
		)
		(pad "2" smd circle
			(at 0.40005 0 270)
			(size 0 0)
			(layers "F.Cu" "F.Mask" "F.Paste")
			(net "PVDD18_S5_P0")
		)
	)
	(footprint ""
		(layer "F.Cu")
		(at 413.928306 -135.41502)
		(property "Reference" "PC1849"
			(at 0 0 0)
			(layer "F.SilkS")
			(hide yes)
			(effects
				(font
					(size 1.27 1.27)
				)
			)
		)
		(property "Value" ""
			(at 0 0 0)
			(layer "F.Fab")
			(effects
				(font
					(size 1.27 1.27)
				)
			)
		)
		(duplicate_pad_numbers_are_jumpers no)
		(fp_line
			(start -1.524 -0.762)
			(end 1.524 -0.762)
			(stroke
				(width 0.1524)
				(type default)
			)
			(layer "F.SilkS")
		)
		(fp_line
			(start -1.524 0.762)
			(end -1.524 -0.762)
			(stroke
				(width 0.1524)
				(type default)
			)
			(layer "F.SilkS")
		)
		(fp_line
			(start 1.524 -0.762)
			(end 1.524 0.762)
			(stroke
				(width 0.1524)
				(type default)
			)
			(layer "F.SilkS")
		)
		(fp_line
			(start 1.524 0.762)
			(end -1.524 0.762)
			(stroke
				(width 0.1524)
				(type default)
			)
			(layer "F.SilkS")
		)
		(fp_line
			(start -1.1049 -0.724916)
			(end -1.1049 0.724916)
			(stroke
				(width 0.1)
				(type default)
			)
			(layer "F.Fab")
		)
		(fp_line
			(start -1.1049 0.724916)
			(end 1.1049 0.724916)
			(stroke
				(width 0.1)
				(type default)
			)
			(layer "F.Fab")
		)
		(fp_line
			(start 1.1049 -0.724916)
			(end -1.1049 -0.724916)
			(stroke
				(width 0.1)
				(type default)
			)
			(layer "F.Fab")
		)
		(fp_line
			(start 1.1049 0.724916)
			(end 1.1049 -0.724916)
			(stroke
				(width 0.1)
				(type default)
			)
			(layer "F.Fab")
		)
		(pad "1" smd rect
			(at -0.889 0 180)
			(size 1.016 1.27)
			(layers "F.Cu" "F.Mask" "F.Paste")
			(net "SW_P5V_AUX_FLT")
		)
		(pad "2" smd rect
			(at 0.889 0 180)
			(size 1.016 1.27)
			(layers "F.Cu" "F.Mask" "F.Paste")
			(net "GND")
		)
	)
	(footprint ""
		(layer "F.Cu")
		(at 69.6976 -390.74598)
		(property "Reference" "R1380"
			(at 0 0 0)
			(layer "F.SilkS")
			(hide yes)
			(effects
				(font
					(size 1.27 1.27)
				)
			)
		)
		(property "Value" ""
			(at 0 0 0)
			(layer "F.Fab")
			(effects
				(font
					(size 1.27 1.27)
				)
			)
		)
		(duplicate_pad_numbers_are_jumpers no)
		(fp_line
			(start -0.32512 -0.175006)
			(end 0.32512 -0.175006)
			(stroke
				(width 0.1)
				(type default)
			)
			(layer "F.Fab")
		)
		(fp_line
			(start -0.32512 0.175006)
			(end -0.32512 -0.175006)
			(stroke
				(width 0.1)
				(type default)
			)
			(layer "F.Fab")
		)
		(fp_line
			(start 0.32512 -0.175006)
			(end 0.32512 0.175006)
			(stroke
				(width 0.1)
				(type default)
			)
			(layer "F.Fab")
		)
		(fp_line
			(start 0.32512 0.175006)
			(end -0.32512 0.175006)
			(stroke
				(width 0.1)
				(type default)
			)
			(layer "F.Fab")
		)
		(pad "1" smd rect
			(at -0.2667 0)
			(size 0.3048 0.381)
			(layers "F.Cu" "F.Mask" "F.Paste")
			(net "JTAG_TRST_RT_CPU1_P0_N")
		)
		(pad "2" smd rect
			(at 0.2667 0 180)
			(size 0.3048 0.381)
			(layers "F.Cu" "F.Mask" "F.Paste")
			(net "GND")
		)
	)
	(footprint ""
		(layer "F.Cu")
		(at 384.7719 -185.748168)
		(property "Reference" "PC180"
			(at 0 0 0)
			(layer "F.SilkS")
			(hide yes)
			(effects
				(font
					(size 1.27 1.27)
				)
			)
		)
		(property "Value" ""
			(at 0 0 0)
			(layer "F.Fab")
			(effects
				(font
					(size 1.27 1.27)
				)
			)
		)
		(duplicate_pad_numbers_are_jumpers no)
		(fp_line
			(start -0.7874 -0.4064)
			(end 0.7874 -0.4064)
			(stroke
				(width 0.1524)
				(type default)
			)
			(layer "F.SilkS")
		)
		(fp_line
			(start -0.7874 0.4064)
			(end -0.7874 -0.4064)
			(stroke
				(width 0.1524)
				(type default)
			)
			(layer "F.SilkS")
		)
		(fp_line
			(start 0.7874 -0.4064)
			(end 0.7874 0.4064)
			(stroke
				(width 0.1524)
				(type default)
			)
			(layer "F.SilkS")
		)
		(fp_line
			(start 0.7874 0.4064)
			(end -0.7874 0.4064)
			(stroke
				(width 0.1524)
				(type default)
			)
			(layer "F.SilkS")
		)
		(fp_line
			(start -0.67945 -0.305054)
			(end -0.12065 -0.305054)
			(stroke
				(width 0.1)
				(type default)
			)
			(layer "F.Fab")
		)
		(fp_line
			(start -0.67945 0.3048)
			(end -0.67945 -0.305054)
			(stroke
				(width 0.1)
				(type default)
			)
			(layer "F.Fab")
		)
		(fp_line
			(start -0.12065 -0.305054)
			(end -0.12065 -0.2794)
			(stroke
				(width 0.1)
				(type default)
			)
			(layer "F.Fab")
		)
		(fp_line
			(start -0.12065 -0.2794)
			(end 0.12065 -0.2794)
			(stroke
				(width 0.1)
				(type default)
			)
			(layer "F.Fab")
		)
		(fp_line
			(start -0.12065 0.2794)
			(end -0.12065 0.3048)
			(stroke
				(width 0.1)
				(type default)
			)
			(layer "F.Fab")
		)
		(fp_line
			(start -0.12065 0.3048)
			(end -0.67945 0.3048)
			(stroke
				(width 0.1)
				(type default)
			)
			(layer "F.Fab")
		)
		(fp_line
			(start 0.120396 0.2794)
			(end -0.12065 0.2794)
			(stroke
				(width 0.1)
				(type default)
			)
			(layer "F.Fab")
		)
		(fp_line
			(start 0.120396 0.3048)
			(end 0.120396 0.2794)
			(stroke
				(width 0.1)
				(type default)
			)
			(layer "F.Fab")
		)
		(fp_line
			(start 0.12065 -0.3048)
			(end 0.67945 -0.3048)
			(stroke
				(width 0.1)
				(type default)
			)
			(layer "F.Fab")
		)
		(fp_line
			(start 0.12065 -0.2794)
			(end 0.12065 -0.3048)
			(stroke
				(width 0.1)
				(type default)
			)
			(layer "F.Fab")
		)
		(fp_line
			(start 0.67945 -0.3048)
			(end 0.67945 0.3048)
			(stroke
				(width 0.1)
				(type default)
			)
			(layer "F.Fab")
		)
		(fp_line
			(start 0.67945 0.3048)
			(end 0.120396 0.3048)
			(stroke
				(width 0.1)
				(type default)
			)
			(layer "F.Fab")
		)
		(pad "1" smd circle
			(at -0.40005 0)
			(size 0 0)
			(layers "F.Cu" "F.Mask" "F.Paste")
			(net "SW_PVDDCR_CPU0_P0_SW3")
		)
		(pad "2" smd circle
			(at 0.40005 0)
			(size 0 0)
			(layers "F.Cu" "F.Mask" "F.Paste")
			(net "SW_PVDDCR_CPU0_P0_SW3_RC")
		)
	)
)
